# T6G (Grand Teton) — schematic netlist excerpt (pin names and nets, part order shuffled) for the footprints in the layout excerpt that follows; sources: Cadence DE-HDL packaged netlist, KiCad conversion of 04192023_DAF0TMB3IC0_F0TG_MB_C_brd_V02_OCP.brd

R2842  Q_RES  4.7K 5% CHIP  pkg 0402LF  page 127 : A = P3V3_AUX ; B = FM_GPU_PWRGD_N
C2507  Q_CAP  22UF 4V 20% X6S  pkg C0402  page 74 : A = PVDDIO_P1 ; B = GND
C418  Q_CAP  1UF 4V 20% X6S  pkg 0201  page 345 : A = P0V9_CPU1_RT2_2A ; B = GND

(kicad_pcb
	(version 20260206)
	(generator "pcbnew")
	(generator_version "10.0")
	(general
		(thickness 1.6)
		(legacy_teardrops no)
	)
	(paper "A4")
	(title_block
		(title "04192023_DAF0TMB3IC0_F0TG_MB_C_brd_V02_OCP.brd")
		(comment 1 "Grand Teton / footprints 7867-7869 of 8354")
	)
	(layers
		(0 "F.Cu" signal "TOP")
		(4 "In1.Cu" signal "GND")
		(6 "In2.Cu" signal "IN1")
		(8 "In3.Cu" signal "GND1")
		(10 "In4.Cu" signal "IN2")
		(12 "In5.Cu" signal "GND2")
		(14 "In6.Cu" signal "IN3")
		(16 "In7.Cu" signal "GND3")
		(18 "In8.Cu" signal "VCC")
		(20 "In9.Cu" signal "VCC1")
		(22 "In10.Cu" signal "GND4")
		(24 "In11.Cu" signal "IN4")
		(26 "In12.Cu" signal "GND5")
		(28 "In13.Cu" signal "IN5")
		(30 "In14.Cu" signal "GND6")
		(32 "In15.Cu" signal "IN6")
		(34 "In16.Cu" signal "GND7")
		(2 "B.Cu" signal "BOTTOM")
		(9 "F.Adhes" user "F.Adhesive")
		(11 "B.Adhes" user "B.Adhesive")
		(13 "F.Paste" user "Package Geometry/Pastemask Top")
		(15 "B.Paste" user "Package Geometry/Pastemask Bottom")
		(5 "F.SilkS" user "Ref Des/Silkscreen Top")
		(7 "B.SilkS" user "Ref Des/Silkscreen Bottom")
		(1 "F.Mask" user "Board Geometry/Soldermask Top")
		(3 "B.Mask" user "Board Geometry/Soldermask Bottom")
		(17 "Dwgs.User" user "User.Drawings")
		(19 "Cmts.User" user "User.Comments")
		(21 "Eco1.User" user "User.Eco1")
		(23 "Eco2.User" user "User.Eco2")
		(25 "Edge.Cuts" user "Board Geometry/Outline")
		(27 "Margin" user)
		(31 "F.CrtYd" user "Package Geometry/Place Bound Top")
		(29 "B.CrtYd" user "Package Geometry/Place Bound Bottom")
		(35 "F.Fab" user "Ref Des/Assembly Top")
		(33 "B.Fab" user "Ref Des/Assembly Bottom")
	)
	(footprint ""
		(layer "B.Cu")
		(at 166.211504 -386.766562 90)
		(property "Reference" "C418"
			(at 0 0 90)
			(layer "B.SilkS")
			(hide yes)
			(effects
				(font
					(size 1.27 1.27)
				)
				(justify mirror)
			)
		)
		(property "Value" ""
			(at 0 0 90)
			(layer "B.Fab")
			(effects
				(font
					(size 1.27 1.27)
				)
				(justify mirror)
			)
		)
		(duplicate_pad_numbers_are_jumpers no)
		(fp_line
			(start 0.299974 -0.150114)
			(end -0.299974 -0.150114)
			(stroke
				(width 0.1)
				(type default)
			)
			(layer "B.Fab")
		)
		(fp_line
			(start -0.299974 -0.150114)
			(end -0.299974 0.150114)
			(stroke
				(width 0.1)
				(type default)
			)
			(layer "B.Fab")
		)
		(fp_line
			(start 0.299974 0.150114)
			(end 0.299974 -0.150114)
			(stroke
				(width 0.1)
				(type default)
			)
			(layer "B.Fab")
		)
		(fp_line
			(start -0.299974 0.150114)
			(end 0.299974 0.150114)
			(stroke
				(width 0.1)
				(type default)
			)
			(layer "B.Fab")
		)
		(pad "1" smd rect
			(at 0.2667 0 270)
			(size 0.3048 0.381)
			(layers "B.Cu" "B.Mask" "B.Paste")
			(net "P0V9_CPU1_RT2_2A")
		)
		(pad "2" smd rect
			(at -0.2667 0 270)
			(size 0.3048 0.381)
			(layers "B.Cu" "B.Mask" "B.Paste")
			(net "GND")
		)
	)
	(footprint ""
		(layer "B.Cu")
		(at 100.478844 -258.830318 180)
		(property "Reference" "C2507"
			(at 0 0 0)
			(layer "B.SilkS")
			(hide yes)
			(effects
				(font
					(size 1.27 1.27)
				)
				(justify mirror)
			)
		)
		(property "Value" ""
			(at 0 0 0)
			(layer "B.Fab")
			(effects
				(font
					(size 1.27 1.27)
				)
				(justify mirror)
			)
		)
		(duplicate_pad_numbers_are_jumpers no)
		(fp_line
			(start 0.7874 0.4064)
			(end 0.7874 -0.4064)
			(stroke
				(width 0.1524)
				(type default)
			)
			(layer "B.SilkS")
		)
		(fp_line
			(start 0.7874 -0.4064)
			(end -0.7874 -0.4064)
			(stroke
				(width 0.1524)
				(type default)
			)
			(layer "B.SilkS")
		)
		(fp_line
			(start -0.7874 0.4064)
			(end 0.7874 0.4064)
			(stroke
				(width 0.1524)
				(type default)
			)
			(layer "B.SilkS")
		)
		(fp_line
			(start -0.7874 -0.4064)
			(end -0.7874 0.4064)
			(stroke
				(width 0.1524)
				(type default)
			)
			(layer "B.SilkS")
		)
		(fp_line
			(start 0.67945 0.3048)
			(end 0.67945 -0.305054)
			(stroke
				(width 0.1)
				(type default)
			)
			(layer "B.Fab")
		)
		(fp_line
			(start 0.67945 -0.305054)
			(end 0.12065 -0.305054)
			(stroke
				(width 0.1)
				(type default)
			)
			(layer "B.Fab")
		)
		(fp_line
			(start 0.12065 0.3048)
			(end 0.67945 0.3048)
			(stroke
				(width 0.1)
				(type default)
			)
			(layer "B.Fab")
		)
		(fp_line
			(start 0.12065 0.2794)
			(end 0.12065 0.3048)
			(stroke
				(width 0.1)
				(type default)
			)
			(layer "B.Fab")
		)
		(fp_line
			(start 0.12065 -0.2794)
			(end -0.12065 -0.2794)
			(stroke
				(width 0.1)
				(type default)
			)
			(layer "B.Fab")
		)
		(fp_line
			(start 0.12065 -0.305054)
			(end 0.12065 -0.2794)
			(stroke
				(width 0.1)
				(type default)
			)
			(layer "B.Fab")
		)
		(fp_line
			(start -0.120396 0.3048)
			(end -0.120396 0.2794)
			(stroke
				(width 0.1)
				(type default)
			)
			(layer "B.Fab")
		)
		(fp_line
			(start -0.120396 0.2794)
			(end 0.12065 0.2794)
			(stroke
				(width 0.1)
				(type default)
			)
			(layer "B.Fab")
		)
		(fp_line
			(start -0.12065 -0.2794)
			(end -0.12065 -0.3048)
			(stroke
				(width 0.1)
				(type default)
			)
			(layer "B.Fab")
		)
		(fp_line
			(start -0.12065 -0.3048)
			(end -0.67945 -0.3048)
			(stroke
				(width 0.1)
				(type default)
			)
			(layer "B.Fab")
		)
		(fp_line
			(start -0.67945 0.3048)
			(end -0.120396 0.3048)
			(stroke
				(width 0.1)
				(type default)
			)
			(layer "B.Fab")
		)
		(fp_line
			(start -0.67945 -0.3048)
			(end -0.67945 0.3048)
			(stroke
				(width 0.1)
				(type default)
			)
			(layer "B.Fab")
		)
		(pad "1" smd circle
			(at 0.40005 0)
			(size 0 0)
			(layers "B.Cu" "B.Mask" "B.Paste")
			(net "PVDDIO_P1")
		)
		(pad "2" smd circle
			(at -0.40005 0)
			(size 0 0)
			(layers "B.Cu" "B.Mask" "B.Paste")
			(net "GND")
		)
	)
	(footprint ""
		(layer "B.Cu")
		(at 46.434502 -424.305984 -90)
		(property "Reference" "R2842"
			(at 0 0 90)
			(layer "B.SilkS")
			(hide yes)
			(effects
				(font
					(size 1.27 1.27)
				)
				(justify mirror)
			)
		)
		(property "Value" ""
			(at 0 0 90)
			(layer "B.Fab")
			(effects
				(font
					(size 1.27 1.27)
				)
				(justify mirror)
			)
		)
		(duplicate_pad_numbers_are_jumpers no)
		(fp_line
			(start -0.7874 0.4064)
			(end 0.7874 0.4064)
			(stroke
				(width 0.1524)
				(type default)
			)
			(layer "B.SilkS")
		)
		(fp_line
			(start 0.7874 0.4064)
			(end 0.7874 -0.4064)
			(stroke
				(width 0.1524)
				(type default)
			)
			(layer "B.SilkS")
		)
		(fp_line
			(start -0.7874 -0.4064)
			(end -0.7874 0.4064)
			(stroke
				(width 0.1524)
				(type default)
			)
			(layer "B.SilkS")
		)
		(fp_line
			(start 0.7874 -0.4064)
			(end -0.7874 -0.4064)
			(stroke
				(width 0.1524)
				(type default)
			)
			(layer "B.SilkS")
		)
		(fp_line
			(start -0.67945 0.3048)
			(end -0.120396 0.3048)
			(stroke
				(width 0.1)
				(type default)
			)
			(layer "B.Fab")
		)
		(fp_line
			(start -0.120396 0.3048)
			(end -0.120396 0.2794)
			(stroke
				(width 0.1)
				(type default)
			)
			(layer "B.Fab")
		)
		(fp_line
			(start 0.12065 0.3048)
			(end 0.67945 0.3048)
			(stroke
				(width 0.1)
				(type default)
			)
			(layer "B.Fab")
		)
		(fp_line
			(start 0.67945 0.3048)
			(end 0.67945 -0.305054)
			(stroke
				(width 0.1)
				(type default)
			)
			(layer "B.Fab")
		)
		(fp_line
			(start -0.120396 0.2794)
			(end 0.12065 0.2794)
			(stroke
				(width 0.1)
				(type default)
			)
			(layer "B.Fab")
		)
		(fp_line
			(start 0.12065 0.2794)
			(end 0.12065 0.3048)
			(stroke
				(width 0.1)
				(type default)
			)
			(layer "B.Fab")
		)
		(fp_line
			(start -0.12065 -0.2794)
			(end -0.12065 -0.3048)
			(stroke
				(width 0.1)
				(type default)
			)
			(layer "B.Fab")
		)
		(fp_line
			(start 0.12065 -0.2794)
			(end -0.12065 -0.2794)
			(stroke
				(width 0.1)
				(type default)
			)
			(layer "B.Fab")
		)
		(fp_line
			(start -0.67945 -0.3048)
			(end -0.67945 0.3048)
			(stroke
				(width 0.1)
				(type default)
			)
			(layer "B.Fab")
		)
		(fp_line
			(start -0.12065 -0.3048)
			(end -0.67945 -0.3048)
			(stroke
				(width 0.1)
				(type default)
			)
			(layer "B.Fab")
		)
		(fp_line
			(start 0.12065 -0.305054)
			(end 0.12065 -0.2794)
			(stroke
				(width 0.1)
				(type default)
			)
			(layer "B.Fab")
		)
		(fp_line
			(start 0.67945 -0.305054)
			(end 0.12065 -0.305054)
			(stroke
				(width 0.1)
				(type default)
			)
			(layer "B.Fab")
		)
		(pad "1" smd circle
			(at 0.40005 0 90)
			(size 0 0)
			(layers "B.Cu" "B.Mask" "B.Paste")
			(net "P3V3_AUX")
		)
		(pad "2" smd circle
			(at -0.40005 0 90)
			(size 0 0)
			(layers "B.Cu" "B.Mask" "B.Paste")
			(net "FM_GPU_PWRGD_N")
		)
	)
)
